(kicad_pcb
	(version 20260206)
	(generator "pcbnew")
	(generator_version "10.0")
	(general
		(thickness 1.6)
		(legacy_teardrops no)
	)
	(paper "A4")
	(title_block
		(title "timecard-production-celestica-r4006 — R4006-B0001-02_R01.brd")
		(comment 1 "Time Appliance Project (Time Card) / footprints 530-535 of 1113")
	)
	(layers
		(0 "F.Cu" signal "TOP")
		(4 "In1.Cu" signal "L02_GND1")
		(6 "In2.Cu" signal "L03_SIG1")
		(8 "In3.Cu" signal "L04_GND2")
		(10 "In4.Cu" signal "L05_VCC1")
		(12 "In5.Cu" signal "L06_VCC2")
		(14 "In6.Cu" signal "L07_GND3")
		(16 "In7.Cu" signal "L08_SIG2")
		(18 "In8.Cu" signal "L09_GND4")
		(2 "B.Cu" signal "BOTTOM")
		(9 "F.Adhes" user "F.Adhesive")
		(11 "B.Adhes" user "B.Adhesive")
		(13 "F.Paste" user "Package Geometry/Pastemask Top")
		(15 "B.Paste" user "Package Geometry/Pastemask Bottom")
		(5 "F.SilkS" user "Ref Des/Silkscreen Top")
		(7 "B.SilkS" user "Ref Des/Silkscreen Bottom")
		(1 "F.Mask" user "Board Geometry/Soldermask Top")
		(3 "B.Mask" user "Board Geometry/Soldermask Bottom")
		(17 "Dwgs.User" user "User.Drawings")
		(19 "Cmts.User" user "User.Comments")
		(21 "Eco1.User" user "User.Eco1")
		(23 "Eco2.User" user "User.Eco2")
		(25 "Edge.Cuts" user "Board Geometry/Outline")
		(27 "Margin" user)
		(31 "F.CrtYd" user "Package Geometry/Place Bound Top")
		(29 "B.CrtYd" user "Package Geometry/Place Bound Bottom")
		(35 "F.Fab" user "Ref Des/Assembly Top")
		(33 "B.Fab" user "Ref Des/Assembly Bottom")
	)
	(footprint ""
		(layer "F.Cu")
		(at 111.125 -100.711)
		(property "Reference" "C314"
			(at 3.175 -3.13563 0)
			(unlocked yes)
			(layer "F.SilkS")
			(effects
				(font
					(size 0.7874 0.5842)
					(thickness 0.1524)
				)
			)
		)
		(property "Value" "VAL*"
			(at 0.0762 2.067306 0)
			(unlocked yes)
			(layer "F.Fab")
			(hide yes)
			(effects
				(font
					(size 0.7874 0.5842)
					(thickness 0.1524)
				)
			)
		)
		(property "Tolerance" "TOL*"
			(at 0.0762 3.032506 0)
			(unlocked yes)
			(layer "Cmts.User")
			(hide yes)
			(effects
				(font
					(size 0.7874 0.5842)
					(thickness 0.1524)
				)
			)
		)
		(property "User Part Number" "PARTNUM*"
			(at 0.1016 4.023106 0)
			(unlocked yes)
			(layer "Cmts.User")
			(hide yes)
			(effects
				(font
					(size 0.7874 0.5842)
					(thickness 0.1524)
				)
			)
		)
		(property "Device Type" "CAPACITOR-G105-0C106-BM,10UF,2A"
			(at 0.0508 1.127506 0)
			(unlocked yes)
			(layer "F.Fab")
			(hide yes)
			(effects
				(font
					(size 0.7874 0.5842)
					(thickness 0.1524)
				)
			)
		)
		(duplicate_pad_numbers_are_jumpers no)
		(fp_line
			(start -1.143 -0.5588)
			(end -1.143 0.5588)
			(stroke
				(width 0.1)
				(type default)
			)
			(layer "F.SilkS")
		)
		(fp_line
			(start -1.143 0.5588)
			(end 1.143 0.5588)
			(stroke
				(width 0.1)
				(type default)
			)
			(layer "F.SilkS")
		)
		(fp_line
			(start 1.143 -0.5588)
			(end -1.143 -0.5588)
			(stroke
				(width 0.1)
				(type default)
			)
			(layer "F.SilkS")
		)
		(fp_line
			(start 1.143 0.5588)
			(end 1.143 -0.5588)
			(stroke
				(width 0.1)
				(type default)
			)
			(layer "F.SilkS")
		)
		(fp_poly
			(pts
				(xy -1.143 0.5588) (xy 1.143 0.5588) (xy 1.143 -0.5588) (xy -1.143 -0.5588)
			)
			(stroke
				(width 0)
				(type default)
			)
			(fill no)
			(layer "F.CrtYd")
		)
		(fp_line
			(start -0.508 -0.3048)
			(end -0.508 0.3048)
			(stroke
				(width 0.1)
				(type default)
			)
			(layer "F.Fab")
		)
		(fp_line
			(start -0.508 0.3048)
			(end 0.508 0.3048)
			(stroke
				(width 0.1)
				(type default)
			)
			(layer "F.Fab")
		)
		(fp_line
			(start 0.508 -0.3048)
			(end -0.508 -0.3048)
			(stroke
				(width 0.1)
				(type default)
			)
			(layer "F.Fab")
		)
		(fp_line
			(start 0.508 0.3048)
			(end 0.508 -0.3048)
			(stroke
				(width 0.1)
				(type default)
			)
			(layer "F.Fab")
		)
		(pad "1" smd rect
			(at -0.5334 0)
			(size 0.7112 0.6096)
			(layers "F.Cu" "F.Mask" "F.Paste")
			(net "XP3R3V_FPGA")
		)
		(pad "2" smd rect
			(at 0.5334 0)
			(size 0.7112 0.6096)
			(layers "F.Cu" "F.Mask" "F.Paste")
			(net "SG")
		)
		(zone
			(layer "F.Cu")
			(hatch none 0.5)
			(connect_pads
				(clearance 0)
			)
			(min_thickness 0.25)
			(keepout
				(tracks not_allowed)
				(vias allowed)
				(pads allowed)
				(copperpour not_allowed)
				(footprints allowed)
			)
			(placement
				(enabled no)
				(sheetname "")
			)
			(fill
				(thermal_gap 0.5)
				(thermal_bridge_width 0.5)
				(island_removal_mode 0)
			)
			(polygon
				(pts
					(xy 111.0488 -100.4062) (xy 111.2012 -100.4062) (xy 111.2012 -101.0158) (xy 111.0488 -101.0158)
				)
			)
		)
		(zone
			(layer "F.Cu")
			(hatch none 0.5)
			(connect_pads
				(clearance 0)
			)
			(min_thickness 0.25)
			(keepout
				(tracks allowed)
				(vias not_allowed)
				(pads allowed)
				(copperpour not_allowed)
				(footprints allowed)
			)
			(placement
				(enabled no)
				(sheetname "")
			)
			(fill
				(thermal_gap 0.5)
				(thermal_bridge_width 0.5)
				(island_removal_mode 0)
			)
			(polygon
				(pts
					(xy 111.0488 -100.4062) (xy 111.2012 -100.4062) (xy 111.2012 -101.0158) (xy 111.0488 -101.0158)
				)
			)
		)
	)
	(footprint ""
		(layer "F.Cu")
		(at 82.677 -93.599 90)
		(property "Reference" "C18"
			(at -3.81 -3.38963 90)
			(unlocked yes)
			(layer "F.SilkS")
			(effects
				(font
					(size 0.7874 0.5842)
					(thickness 0.1524)
				)
			)
		)
		(property "Value" "VAL*"
			(at 0.0762 2.067306 90)
			(unlocked yes)
			(layer "F.Fab")
			(hide yes)
			(effects
				(font
					(size 0.7874 0.5842)
					(thickness 0.1524)
				)
			)
		)
		(property "Tolerance" "TOL*"
			(at 0.0762 3.032506 90)
			(unlocked yes)
			(layer "Cmts.User")
			(hide yes)
			(effects
				(font
					(size 0.7874 0.5842)
					(thickness 0.1524)
				)
			)
		)
		(property "User Part Number" "PARTNUM*"
			(at 0.1016 4.023106 90)
			(unlocked yes)
			(layer "Cmts.User")
			(hide yes)
			(effects
				(font
					(size 0.7874 0.5842)
					(thickness 0.1524)
				)
			)
		)
		(property "Device Type" "CAPACITOR-G105-0B104-CK,0.1UF,A"
			(at 0.0508 1.127506 90)
			(unlocked yes)
			(layer "F.Fab")
			(hide yes)
			(effects
				(font
					(size 0.7874 0.5842)
					(thickness 0.1524)
				)
			)
		)
		(duplicate_pad_numbers_are_jumpers no)
		(fp_line
			(start 1.143 -0.5588)
			(end -1.143 -0.5588)
			(stroke
				(width 0.1)
				(type default)
			)
			(layer "F.SilkS")
		)
		(fp_line
			(start -1.143 -0.5588)
			(end -1.143 0.5588)
			(stroke
				(width 0.1)
				(type default)
			)
			(layer "F.SilkS")
		)
		(fp_line
			(start 1.143 0.5588)
			(end 1.143 -0.5588)
			(stroke
				(width 0.1)
				(type default)
			)
			(layer "F.SilkS")
		)
		(fp_line
			(start -1.143 0.5588)
			(end 1.143 0.5588)
			(stroke
				(width 0.1)
				(type default)
			)
			(layer "F.SilkS")
		)
		(fp_rect
			(start -1.143 -0.5588)
			(end 1.143 0.5588)
			(stroke
				(width 0)
				(type default)
			)
			(fill no)
			(layer "F.CrtYd")
		)
		(fp_line
			(start 0.508 -0.3048)
			(end -0.508 -0.3048)
			(stroke
				(width 0.1)
				(type default)
			)
			(layer "F.Fab")
		)
		(fp_line
			(start -0.508 -0.3048)
			(end -0.508 0.3048)
			(stroke
				(width 0.1)
				(type default)
			)
			(layer "F.Fab")
		)
		(fp_line
			(start 0.508 0.3048)
			(end 0.508 -0.3048)
			(stroke
				(width 0.1)
				(type default)
			)
			(layer "F.Fab")
		)
		(fp_line
			(start -0.508 0.3048)
			(end 0.508 0.3048)
			(stroke
				(width 0.1)
				(type default)
			)
			(layer "F.Fab")
		)
		(pad "1" smd rect
			(at -0.5334 0 90)
			(size 0.7112 0.6096)
			(layers "F.Cu" "F.Mask" "F.Paste")
			(net "XP3R3V")
		)
		(pad "2" smd rect
			(at 0.5334 0 90)
			(size 0.7112 0.6096)
			(layers "F.Cu" "F.Mask" "F.Paste")
			(net "SG")
		)
		(zone
			(layer "F.Cu")
			(hatch none 0.5)
			(connect_pads
				(clearance 0)
			)
			(min_thickness 0.25)
			(keepout
				(tracks allowed)
				(vias not_allowed)
				(pads allowed)
				(copperpour not_allowed)
				(footprints allowed)
			)
			(placement
				(enabled no)
				(sheetname "")
			)
			(fill
				(thermal_gap 0.5)
				(thermal_bridge_width 0.5)
				(island_removal_mode 0)
			)
			(polygon
				(pts
					(xy 82.3722 -93.5228) (xy 82.9818 -93.5228) (xy 82.9818 -93.6752) (xy 82.3722 -93.6752)
				)
			)
		)
	)
	(footprint ""
		(layer "F.Cu")
		(at 38.989 -78.867 -90)
		(property "Reference" "TP3"
			(at 0 0 270)
			(layer "F.SilkS")
			(hide yes)
			(effects
				(font
					(size 1.27 1.27)
				)
			)
		)
		(property "Value" ""
			(at 0 0 270)
			(layer "F.Fab")
			(effects
				(font
					(size 1.27 1.27)
				)
			)
		)
		(property "Device Type" "TP_PIONT-TP010CT020B030_PTH-TPA"
			(at -1.341882 0.996696 270)
			(unlocked yes)
			(layer "F.Fab")
			(hide yes)
			(effects
				(font
					(size 0.7874 0.5842)
					(thickness 0.1524)
				)
				(justify left)
			)
		)
		(duplicate_pad_numbers_are_jumpers no)
		(fp_poly
			(pts
				(arc
					(start 0 -0.889)
					(mid 0 0.889)
					(end 0 -0.889)
				)
			)
			(stroke
				(width 0)
				(type default)
			)
			(fill no)
			(layer "B.CrtYd")
		)
		(fp_poly
			(pts
				(arc
					(start 0 -0.889)
					(mid 0 0.889)
					(end 0 -0.889)
				)
			)
			(stroke
				(width 0)
				(type default)
			)
			(fill no)
			(layer "F.CrtYd")
		)
		(pad "1" thru_hole circle
			(at 0 0 270)
			(size 0.508 0.508)
			(drill 0.254)
			(layers "*.Cu" "*.Mask")
			(remove_unused_layers no)
			(net "XP3R3V_FT4232")
			(clearance 0.1016)
			(padstack
				(mode front_inner_back)
				(layer "Inner"
					(shape circle)
					(size 0.508 0.508)
					(clearance 0.1016)
				)
				(layer "B.Cu"
					(shape circle)
					(size 0.762 0.762)
					(clearance -0.0254)
				)
			)
		)
	)
	(footprint ""
		(layer "F.Cu")
		(at 12.8778 -68.072)
		(property "Reference" "C317"
			(at 0.3302 -5.67563 0)
			(unlocked yes)
			(layer "F.SilkS")
			(effects
				(font
					(size 0.7874 0.5842)
					(thickness 0.1524)
				)
			)
		)
		(property "Value" "VAL*"
			(at 0.193548 2.13614 0)
			(unlocked yes)
			(layer "F.Fab")
			(hide yes)
			(effects
				(font
					(size 0.7874 0.5842)
					(thickness 0.1524)
				)
			)
		)
		(property "User Part Number" "PARTNUM*"
			(at 0.216154 4.185666 0)
			(unlocked yes)
			(layer "Cmts.User")
			(hide yes)
			(effects
				(font
					(size 0.7874 0.5842)
					(thickness 0.1524)
				)
			)
		)
		(property "Device Type" "CAPACITOR-G104-0A180-FJ,18PF,5%"
			(at 0.184404 1.180592 0)
			(unlocked yes)
			(layer "F.Fab")
			(hide yes)
			(effects
				(font
					(size 0.7874 0.5842)
					(thickness 0.1524)
				)
			)
		)
		(property "Tolerance" "TOL*"
			(at 0.216154 3.1496 0)
			(unlocked yes)
			(layer "Cmts.User")
			(hide yes)
			(effects
				(font
					(size 0.7874 0.5842)
					(thickness 0.1524)
				)
			)
		)
		(duplicate_pad_numbers_are_jumpers no)
		(fp_line
			(start -0.671322 -0.4445)
			(end 0.671322 -0.4445)
			(stroke
				(width 0.1)
				(type default)
			)
			(layer "F.SilkS")
		)
		(fp_line
			(start -0.671322 0.4445)
			(end -0.671322 -0.4445)
			(stroke
				(width 0.1)
				(type default)
			)
			(layer "F.SilkS")
		)
		(fp_line
			(start 0.671322 -0.4445)
			(end 0.671322 0.4445)
			(stroke
				(width 0.1)
				(type default)
			)
			(layer "F.SilkS")
		)
		(fp_line
			(start 0.671322 0.4445)
			(end -0.671322 0.4445)
			(stroke
				(width 0.1)
				(type default)
			)
			(layer "F.SilkS")
		)
		(fp_rect
			(start -0.671322 0.4445)
			(end 0.671322 -0.4445)
			(stroke
				(width 0)
				(type default)
			)
			(fill no)
			(layer "F.CrtYd")
		)
		(fp_line
			(start -0.31496 -0.1651)
			(end -0.31496 0.1651)
			(stroke
				(width 0.1)
				(type default)
			)
			(layer "F.Fab")
		)
		(fp_line
			(start -0.31496 0.1651)
			(end 0.31496 0.1651)
			(stroke
				(width 0.1)
				(type default)
			)
			(layer "F.Fab")
		)
		(fp_line
			(start 0.31496 -0.1651)
			(end -0.31496 -0.1651)
			(stroke
				(width 0.1)
				(type default)
			)
			(layer "F.Fab")
		)
		(fp_line
			(start 0.31496 0.1651)
			(end 0.31496 -0.1651)
			(stroke
				(width 0.1)
				(type default)
			)
			(layer "F.Fab")
		)
		(pad "1" smd rect
			(at -0.264922 0)
			(size 0.3048 0.381)
			(layers "F.Cu" "F.Mask" "F.Paste")
			(net "SG")
		)
		(pad "2" smd rect
			(at 0.264922 0)
			(size 0.3048 0.381)
			(layers "F.Cu" "F.Mask" "F.Paste")
			(net "UNNAMED_12_CAPACITOR_I328_2")
		)
		(zone
			(layer "F.Cu")
			(hatch none 0.5)
			(connect_pads
				(clearance 0)
			)
			(min_thickness 0.25)
			(keepout
				(tracks allowed)
				(vias not_allowed)
				(pads allowed)
				(copperpour not_allowed)
				(footprints allowed)
			)
			(placement
				(enabled no)
				(sheetname "")
			)
			(fill
				(thermal_gap 0.5)
				(thermal_bridge_width 0.5)
				(island_removal_mode 0)
			)
			(polygon
				(pts
					(xy 12.765278 -68.2625) (xy 12.765278 -67.8815) (xy 12.990322 -67.8815) (xy 12.990322 -68.2625)
				)
			)
		)
		(zone
			(layer "F.Cu")
			(hatch none 0.5)
			(connect_pads
				(clearance 0)
			)
			(min_thickness 0.25)
			(keepout
				(tracks not_allowed)
				(vias allowed)
				(pads allowed)
				(copperpour not_allowed)
				(footprints allowed)
			)
			(placement
				(enabled no)
				(sheetname "")
			)
			(fill
				(thermal_gap 0.5)
				(thermal_bridge_width 0.5)
				(island_removal_mode 0)
			)
			(polygon
				(pts
					(xy 12.765278 -67.8815) (xy 12.990322 -67.8815) (xy 12.990322 -68.2625) (xy 12.765278 -68.2625)
				)
			)
		)
	)
	(footprint ""
		(layer "F.Cu")
		(at 95.1484 -45.2628)
		(property "Reference" "TP47"
			(at -0.80645 1.27 90)
			(unlocked yes)
			(layer "F.SilkS")
			(effects
				(font
					(size 0.635 0.4064)
					(thickness 0.1524)
				)
				(justify left)
			)
		)
		(property "Value" ""
			(at 0 0 0)
			(layer "F.Fab")
			(effects
				(font
					(size 1.27 1.27)
				)
			)
		)
		(property "Device Type" "TP_PIONT-TP010CT020B030_PTH-TPA"
			(at -1.341882 0.996696 0)
			(unlocked yes)
			(layer "F.Fab")
			(hide yes)
			(effects
				(font
					(size 0.7874 0.5842)
					(thickness 0.000001)
				)
				(justify left)
			)
		)
		(duplicate_pad_numbers_are_jumpers no)
		(fp_poly
			(pts
				(arc
					(start 0.889 0)
					(mid -0.889 0)
					(end 0.889 0)
				)
			)
			(stroke
				(width 0)
				(type default)
			)
			(fill no)
			(layer "B.CrtYd")
		)
		(fp_poly
			(pts
				(arc
					(start 0.889 0)
					(mid -0.889 0)
					(end 0.889 0)
				)
			)
			(stroke
				(width 0)
				(type default)
			)
			(fill no)
			(layer "F.CrtYd")
		)
		(pad "1" thru_hole circle
			(at 0 0)
			(size 0.508 0.508)
			(drill 0.254)
			(layers "*.Cu" "*.Mask")
			(remove_unused_layers no)
			(net "FPGA_MGTRREF")
			(clearance 0.1016)
			(padstack
				(mode front_inner_back)
				(layer "Inner"
					(shape circle)
					(size 0.508 0.508)
					(clearance 0.1016)
				)
				(layer "B.Cu"
					(shape circle)
					(size 0.762 0.762)
					(clearance -0.0254)
				)
			)
		)
	)
	(footprint ""
		(layer "F.Cu")
		(at 32.021018 -46.746922)
		(property "Reference" "MAC_PIN2"
			(at 0.127762 2.580132 0)
			(unlocked yes)
			(layer "F.SilkS")
			(effects
				(font
					(size 0.7874 0.5842)
					(thickness 0.1524)
				)
			)
		)
		(property "Value" ""
			(at 0 0 0)
			(layer "F.Fab")
			(effects
				(font
					(size 1.27 1.27)
				)
			)
		)
		(property "User Part Number" "PARTNUM*"
			(at 0 3.826764 0)
			(unlocked yes)
			(layer "Cmts.User")
			(hide yes)
			(effects
				(font
					(size 0.7874 0.5842)
					(thickness 0.1524)
				)
			)
		)
		(property "Device Type" "NUT-A200-00029-FB"
			(at 0 2.632964 0)
			(unlocked yes)
			(layer "F.Fab")
			(hide yes)
			(effects
				(font
					(size 0.7874 0.5842)
					(thickness 0.1524)
				)
			)
		)
		(duplicate_pad_numbers_are_jumpers no)
		(fp_circle
			(center 0 0)
			(end 1.524 0)
			(stroke
				(width 0.1)
				(type default)
			)
			(fill no)
			(layer "F.SilkS")
		)
		(fp_poly
			(pts
				(arc
					(start -1.260856 -0.1524)
					(mid -0.898049 -0.898049)
					(end -0.1524 -1.260856)
				)
				(arc
					(start -0.1524 -0.991616)
					(mid -0.709411 -0.709411)
					(end -0.991616 -0.1524)
				)
			)
			(stroke
				(width 0)
				(type default)
			)
			(fill yes)
			(layer "F.Paste")
		)
		(fp_poly
			(pts
				(arc
					(start -0.1524 1.260856)
					(mid -0.898049 0.898049)
					(end -1.260856 0.1524)
				)
				(arc
					(start -0.991616 0.1524)
					(mid -0.709411 0.709411)
					(end -0.1524 0.991616)
				)
			)
			(stroke
				(width 0)
				(type default)
			)
			(fill yes)
			(layer "F.Paste")
		)
		(fp_poly
			(pts
				(arc
					(start 0.1524 -1.260856)
					(mid 0.898049 -0.898049)
					(end 1.260856 -0.1524)
				)
				(arc
					(start 0.991616 -0.1524)
					(mid 0.709411 -0.709411)
					(end 0.1524 -0.991616)
				)
			)
			(stroke
				(width 0)
				(type default)
			)
			(fill yes)
			(layer "F.Paste")
		)
		(fp_poly
			(pts
				(arc
					(start 1.260856 0.1524)
					(mid 0.898049 0.898049)
					(end 0.1524 1.260856)
				)
				(arc
					(start 0.1524 0.991616)
					(mid 0.709411 0.709411)
					(end 0.991616 0.1524)
				)
			)
			(stroke
				(width 0)
				(type default)
			)
			(fill yes)
			(layer "F.Paste")
		)
		(fp_poly
			(pts
				(arc
					(start 6.35 0)
					(mid -6.35 0)
					(end 6.35 0)
				)
			)
			(stroke
				(width 0)
				(type default)
			)
			(fill no)
			(layer "B.CrtYd")
		)
		(fp_poly
			(pts
				(arc
					(start 1.778 0)
					(mid -1.778 0)
					(end 1.778 0)
				)
			)
			(stroke
				(width 0)
				(type default)
			)
			(fill no)
			(layer "F.CrtYd")
		)
		(fp_circle
			(center 0 0)
			(end 1.1684 0)
			(stroke
				(width 0.1)
				(type default)
			)
			(fill no)
			(layer "F.Fab")
		)
		(pad "1" thru_hole circle
			(at 0 0)
			(size 2.54 2.54)
			(drill 2.0066)
			(layers "*.Cu" "*.Mask")
			(remove_unused_layers no)
			(net "SG")
			(thermal_gap 0.0254)
			(padstack
				(mode front_inner_back)
				(layer "Inner"
					(shape circle)
					(size 2.54 2.54)
					(clearance 0.0254)
				)
				(layer "B.Cu"
					(shape circle)
					(size 2.54 2.54)
				)
			)
		)
	)
)
